(kicad_pcb
	(version 20260206)
	(generator "pcbnew")
	(generator_version "10.0")
	(general
		(thickness 1.6)
		(legacy_teardrops no)
	)
	(paper "A4")
	(title_block
		(title "04192023_DAF0TMB3IC0_F0TG_MB_C_brd_V02_OCP.brd")
		(comment 1 "Grand Teton / footprints 4020-4025 of 8354")
	)
	(layers
		(0 "F.Cu" signal "TOP")
		(4 "In1.Cu" signal "GND")
		(6 "In2.Cu" signal "IN1")
		(8 "In3.Cu" signal "GND1")
		(10 "In4.Cu" signal "IN2")
		(12 "In5.Cu" signal "GND2")
		(14 "In6.Cu" signal "IN3")
		(16 "In7.Cu" signal "GND3")
		(18 "In8.Cu" signal "VCC")
		(20 "In9.Cu" signal "VCC1")
		(22 "In10.Cu" signal "GND4")
		(24 "In11.Cu" signal "IN4")
		(26 "In12.Cu" signal "GND5")
		(28 "In13.Cu" signal "IN5")
		(30 "In14.Cu" signal "GND6")
		(32 "In15.Cu" signal "IN6")
		(34 "In16.Cu" signal "GND7")
		(2 "B.Cu" signal "BOTTOM")
		(9 "F.Adhes" user "F.Adhesive")
		(11 "B.Adhes" user "B.Adhesive")
		(13 "F.Paste" user "Package Geometry/Pastemask Top")
		(15 "B.Paste" user "Package Geometry/Pastemask Bottom")
		(5 "F.SilkS" user "Ref Des/Silkscreen Top")
		(7 "B.SilkS" user "Ref Des/Silkscreen Bottom")
		(1 "F.Mask" user "Board Geometry/Soldermask Top")
		(3 "B.Mask" user "Board Geometry/Soldermask Bottom")
		(17 "Dwgs.User" user "User.Drawings")
		(19 "Cmts.User" user "User.Comments")
		(21 "Eco1.User" user "User.Eco1")
		(23 "Eco2.User" user "User.Eco2")
		(25 "Edge.Cuts" user "Board Geometry/Outline")
		(27 "Margin" user)
		(31 "F.CrtYd" user "Package Geometry/Place Bound Top")
		(29 "B.CrtYd" user "Package Geometry/Place Bound Bottom")
		(35 "F.Fab" user "Ref Des/Assembly Top")
		(33 "B.Fab" user "Ref Des/Assembly Bottom")
	)
	(footprint ""
		(layer "F.Cu")
		(at 205.232 -130.048)
		(property "Reference" "R487"
			(at 0 0 0)
			(layer "F.SilkS")
			(hide yes)
			(effects
				(font
					(size 1.27 1.27)
				)
			)
		)
		(property "Value" ""
			(at 0 0 0)
			(layer "F.Fab")
			(effects
				(font
					(size 1.27 1.27)
				)
			)
		)
		(duplicate_pad_numbers_are_jumpers no)
		(fp_line
			(start -0.7874 -0.4064)
			(end 0.7874 -0.4064)
			(stroke
				(width 0.1524)
				(type default)
			)
			(layer "F.SilkS")
		)
		(fp_line
			(start -0.7874 0.4064)
			(end -0.7874 -0.4064)
			(stroke
				(width 0.1524)
				(type default)
			)
			(layer "F.SilkS")
		)
		(fp_line
			(start 0.7874 -0.4064)
			(end 0.7874 0.4064)
			(stroke
				(width 0.1524)
				(type default)
			)
			(layer "F.SilkS")
		)
		(fp_line
			(start 0.7874 0.4064)
			(end -0.7874 0.4064)
			(stroke
				(width 0.1524)
				(type default)
			)
			(layer "F.SilkS")
		)
		(fp_line
			(start -0.67945 -0.305054)
			(end -0.12065 -0.305054)
			(stroke
				(width 0.1)
				(type default)
			)
			(layer "F.Fab")
		)
		(fp_line
			(start -0.67945 0.3048)
			(end -0.67945 -0.305054)
			(stroke
				(width 0.1)
				(type default)
			)
			(layer "F.Fab")
		)
		(fp_line
			(start -0.12065 -0.305054)
			(end -0.12065 -0.2794)
			(stroke
				(width 0.1)
				(type default)
			)
			(layer "F.Fab")
		)
		(fp_line
			(start -0.12065 -0.2794)
			(end 0.12065 -0.2794)
			(stroke
				(width 0.1)
				(type default)
			)
			(layer "F.Fab")
		)
		(fp_line
			(start -0.12065 0.2794)
			(end -0.12065 0.3048)
			(stroke
				(width 0.1)
				(type default)
			)
			(layer "F.Fab")
		)
		(fp_line
			(start -0.12065 0.3048)
			(end -0.67945 0.3048)
			(stroke
				(width 0.1)
				(type default)
			)
			(layer "F.Fab")
		)
		(fp_line
			(start 0.120396 0.2794)
			(end -0.12065 0.2794)
			(stroke
				(width 0.1)
				(type default)
			)
			(layer "F.Fab")
		)
		(fp_line
			(start 0.120396 0.3048)
			(end 0.120396 0.2794)
			(stroke
				(width 0.1)
				(type default)
			)
			(layer "F.Fab")
		)
		(fp_line
			(start 0.12065 -0.3048)
			(end 0.67945 -0.3048)
			(stroke
				(width 0.1)
				(type default)
			)
			(layer "F.Fab")
		)
		(fp_line
			(start 0.12065 -0.2794)
			(end 0.12065 -0.3048)
			(stroke
				(width 0.1)
				(type default)
			)
			(layer "F.Fab")
		)
		(fp_line
			(start 0.67945 -0.3048)
			(end 0.67945 0.3048)
			(stroke
				(width 0.1)
				(type default)
			)
			(layer "F.Fab")
		)
		(fp_line
			(start 0.67945 0.3048)
			(end 0.120396 0.3048)
			(stroke
				(width 0.1)
				(type default)
			)
			(layer "F.Fab")
		)
		(pad "1" smd circle
			(at -0.40005 0)
			(size 0 0)
			(layers "F.Cu" "F.Mask" "F.Paste")
			(net "SW_P3V3_EN")
		)
		(pad "2" smd circle
			(at 0.40005 0)
			(size 0 0)
			(layers "F.Cu" "F.Mask" "F.Paste")
			(net "SW_P3V3_EN_R")
		)
	)
	(footprint ""
		(layer "F.Cu")
		(at 269.023084 -332.029562)
		(property "Reference" "PR52"
			(at 0 0 0)
			(layer "F.SilkS")
			(hide yes)
			(effects
				(font
					(size 1.27 1.27)
				)
			)
		)
		(property "Value" ""
			(at 0 0 0)
			(layer "F.Fab")
			(effects
				(font
					(size 1.27 1.27)
				)
			)
		)
		(duplicate_pad_numbers_are_jumpers no)
		(fp_line
			(start -0.7874 -0.4064)
			(end 0.7874 -0.4064)
			(stroke
				(width 0.1524)
				(type default)
			)
			(layer "F.SilkS")
		)
		(fp_line
			(start -0.7874 0.4064)
			(end -0.7874 -0.4064)
			(stroke
				(width 0.1524)
				(type default)
			)
			(layer "F.SilkS")
		)
		(fp_line
			(start 0.7874 -0.4064)
			(end 0.7874 0.4064)
			(stroke
				(width 0.1524)
				(type default)
			)
			(layer "F.SilkS")
		)
		(fp_line
			(start 0.7874 0.4064)
			(end -0.7874 0.4064)
			(stroke
				(width 0.1524)
				(type default)
			)
			(layer "F.SilkS")
		)
		(fp_line
			(start -0.67945 -0.305054)
			(end -0.12065 -0.305054)
			(stroke
				(width 0.1)
				(type default)
			)
			(layer "F.Fab")
		)
		(fp_line
			(start -0.67945 0.3048)
			(end -0.67945 -0.305054)
			(stroke
				(width 0.1)
				(type default)
			)
			(layer "F.Fab")
		)
		(fp_line
			(start -0.12065 -0.305054)
			(end -0.12065 -0.2794)
			(stroke
				(width 0.1)
				(type default)
			)
			(layer "F.Fab")
		)
		(fp_line
			(start -0.12065 -0.2794)
			(end 0.12065 -0.2794)
			(stroke
				(width 0.1)
				(type default)
			)
			(layer "F.Fab")
		)
		(fp_line
			(start -0.12065 0.2794)
			(end -0.12065 0.3048)
			(stroke
				(width 0.1)
				(type default)
			)
			(layer "F.Fab")
		)
		(fp_line
			(start -0.12065 0.3048)
			(end -0.67945 0.3048)
			(stroke
				(width 0.1)
				(type default)
			)
			(layer "F.Fab")
		)
		(fp_line
			(start 0.120396 0.2794)
			(end -0.12065 0.2794)
			(stroke
				(width 0.1)
				(type default)
			)
			(layer "F.Fab")
		)
		(fp_line
			(start 0.120396 0.3048)
			(end 0.120396 0.2794)
			(stroke
				(width 0.1)
				(type default)
			)
			(layer "F.Fab")
		)
		(fp_line
			(start 0.12065 -0.3048)
			(end 0.67945 -0.3048)
			(stroke
				(width 0.1)
				(type default)
			)
			(layer "F.Fab")
		)
		(fp_line
			(start 0.12065 -0.2794)
			(end 0.12065 -0.3048)
			(stroke
				(width 0.1)
				(type default)
			)
			(layer "F.Fab")
		)
		(fp_line
			(start 0.67945 -0.3048)
			(end 0.67945 0.3048)
			(stroke
				(width 0.1)
				(type default)
			)
			(layer "F.Fab")
		)
		(fp_line
			(start 0.67945 0.3048)
			(end 0.120396 0.3048)
			(stroke
				(width 0.1)
				(type default)
			)
			(layer "F.Fab")
		)
		(pad "1" smd circle
			(at -0.40005 0)
			(size 0 0)
			(layers "F.Cu" "F.Mask" "F.Paste")
			(net "VSENSE_PVDDIO_P0_DP")
		)
		(pad "2" smd circle
			(at 0.40005 0)
			(size 0 0)
			(layers "F.Cu" "F.Mask" "F.Paste")
			(net "PVDDIO_P0")
		)
	)
	(footprint ""
		(layer "F.Cu")
		(at 247.591072 -385.27736 90)
		(property "Reference" "PPQ2"
			(at -7.438644 -2.150872 0)
			(unlocked yes)
			(layer "F.SilkS")
			(effects
				(font
					(size 0.7874 0.5842)
					(thickness 0.1524)
				)
				(justify left)
			)
		)
		(property "Value" ""
			(at 0 0 90)
			(layer "F.Fab")
			(effects
				(font
					(size 1.27 1.27)
				)
			)
		)
		(duplicate_pad_numbers_are_jumpers no)
		(fp_line
			(start 2.350008 -2.649982)
			(end 2.350008 -2.4892)
			(stroke
				(width 0.1524)
				(type default)
			)
			(layer "F.SilkS")
		)
		(fp_line
			(start -2.350008 -2.649982)
			(end 2.350008 -2.649982)
			(stroke
				(width 0.1524)
				(type default)
			)
			(layer "F.SilkS")
		)
		(fp_line
			(start -2.350008 -2.4384)
			(end -2.350008 -2.649982)
			(stroke
				(width 0.1524)
				(type default)
			)
			(layer "F.SilkS")
		)
		(fp_line
			(start 2.350008 2.4892)
			(end 2.350008 2.649982)
			(stroke
				(width 0.1524)
				(type default)
			)
			(layer "F.SilkS")
		)
		(fp_line
			(start 2.350008 2.649982)
			(end -2.350008 2.649982)
			(stroke
				(width 0.1524)
				(type default)
			)
			(layer "F.SilkS")
		)
		(fp_line
			(start -2.350008 2.649982)
			(end -2.350008 2.413)
			(stroke
				(width 0.1524)
				(type default)
			)
			(layer "F.SilkS")
		)
		(fp_poly
			(pts
				(xy -3.45313 -3.467354) (xy -2.653538 -3.434588) (xy -3.115056 -2.411222)
			)
			(stroke
				(width 0)
				(type default)
			)
			(fill yes)
			(layer "F.SilkS")
		)
		(fp_line
			(start 2.350008 -2.649982)
			(end 2.350008 2.649982)
			(stroke
				(width 0.1)
				(type default)
			)
			(layer "F.Fab")
		)
		(fp_line
			(start -2.350008 -2.649982)
			(end 2.350008 -2.649982)
			(stroke
				(width 0.1)
				(type default)
			)
			(layer "F.Fab")
		)
		(fp_line
			(start 2.350008 2.649982)
			(end -2.350008 2.649982)
			(stroke
				(width 0.1)
				(type default)
			)
			(layer "F.Fab")
		)
		(fp_line
			(start -2.350008 2.649982)
			(end -2.350008 -2.649982)
			(stroke
				(width 0.1)
				(type default)
			)
			(layer "F.Fab")
		)
		(fp_poly
			(pts
				(xy -3.717544 -1.905) (xy -4.758944 -2.3241) (xy -4.758944 -1.524)
			)
			(stroke
				(width 0)
				(type default)
			)
			(fill yes)
			(layer "F.Fab")
		)
		(pad "1" smd rect
			(at -2.999994 -1.905)
			(size 0.7112 1.1684)
			(layers "F.Cu" "F.Mask" "F.Paste")
			(net "P12V_AUX")
		)
		(pad "2" smd rect
			(at -2.999994 -0.635)
			(size 0.7112 1.1684)
			(layers "F.Cu" "F.Mask" "F.Paste")
			(net "P12V_AUX")
		)
		(pad "3" smd rect
			(at -2.999994 0.635)
			(size 0.7112 1.1684)
			(layers "F.Cu" "F.Mask" "F.Paste")
			(net "P12V_AUX")
		)
		(pad "4" smd rect
			(at -2.999994 1.905)
			(size 0.7112 1.1684)
			(layers "F.Cu" "F.Mask" "F.Paste")
			(net "P12V_HSC_GATE_G6")
		)
		(pad "5" smd circle
			(at 0.925068 0)
			(size 0 0)
			(layers "F.Cu" "F.Mask" "F.Paste")
			(net "P12V_MAIN_R")
		)
		(zone
			(layer "F.Cu")
			(hatch none 0.5)
			(connect_pads
				(clearance 0)
			)
			(min_thickness 0.25)
			(keepout
				(tracks not_allowed)
				(vias allowed)
				(pads allowed)
				(copperpour not_allowed)
				(footprints allowed)
			)
			(placement
				(enabled no)
				(sheetname "")
			)
			(fill
				(thermal_gap 0.5)
				(thermal_bridge_width 0.5)
				(island_removal_mode 0)
			)
			(polygon
				(pts
					(xy 244.949472 -383.7178) (xy 250.232672 -383.7178) (xy 250.232672 -382.92786) (xy 244.949472 -382.92786)
				)
			)
		)
	)
	(footprint ""
		(layer "F.Cu")
		(at 199.941942 -346.023184 180)
		(property "Reference" "PC119"
			(at 0 0 180)
			(layer "F.SilkS")
			(hide yes)
			(effects
				(font
					(size 1.27 1.27)
				)
			)
		)
		(property "Value" ""
			(at 0 0 180)
			(layer "F.Fab")
			(effects
				(font
					(size 1.27 1.27)
				)
			)
		)
		(duplicate_pad_numbers_are_jumpers no)
		(fp_line
			(start 1.524 0.762)
			(end -1.524 0.762)
			(stroke
				(width 0.1524)
				(type default)
			)
			(layer "F.SilkS")
		)
		(fp_line
			(start 1.524 -0.762)
			(end 1.524 0.762)
			(stroke
				(width 0.1524)
				(type default)
			)
			(layer "F.SilkS")
		)
		(fp_line
			(start -1.524 0.762)
			(end -1.524 -0.762)
			(stroke
				(width 0.1524)
				(type default)
			)
			(layer "F.SilkS")
		)
		(fp_line
			(start -1.524 -0.762)
			(end 1.524 -0.762)
			(stroke
				(width 0.1524)
				(type default)
			)
			(layer "F.SilkS")
		)
		(fp_line
			(start 1.1049 0.724916)
			(end 1.1049 -0.724916)
			(stroke
				(width 0.1)
				(type default)
			)
			(layer "F.Fab")
		)
		(fp_line
			(start 1.1049 -0.724916)
			(end -1.1049 -0.724916)
			(stroke
				(width 0.1)
				(type default)
			)
			(layer "F.Fab")
		)
		(fp_line
			(start -1.1049 0.724916)
			(end 1.1049 0.724916)
			(stroke
				(width 0.1)
				(type default)
			)
			(layer "F.Fab")
		)
		(fp_line
			(start -1.1049 -0.724916)
			(end -1.1049 0.724916)
			(stroke
				(width 0.1)
				(type default)
			)
			(layer "F.Fab")
		)
		(pad "1" smd rect
			(at -0.889 0)
			(size 1.016 1.27)
			(layers "F.Cu" "F.Mask" "F.Paste")
			(net "SW_P12V_AUX_PVDD_33_S5_FLT")
		)
		(pad "2" smd rect
			(at 0.889 0)
			(size 1.016 1.27)
			(layers "F.Cu" "F.Mask" "F.Paste")
			(net "GND")
		)
	)
	(footprint ""
		(layer "F.Cu")
		(at 205.147926 -331.016864 90)
		(property "Reference" "PC136"
			(at 0 0 90)
			(layer "F.SilkS")
			(hide yes)
			(effects
				(font
					(size 1.27 1.27)
				)
			)
		)
		(property "Value" ""
			(at 0 0 90)
			(layer "F.Fab")
			(effects
				(font
					(size 1.27 1.27)
				)
			)
		)
		(duplicate_pad_numbers_are_jumpers no)
		(fp_line
			(start 0.7874 -0.4064)
			(end 0.7874 0.4064)
			(stroke
				(width 0.1524)
				(type default)
			)
			(layer "F.SilkS")
		)
		(fp_line
			(start -0.7874 -0.4064)
			(end 0.7874 -0.4064)
			(stroke
				(width 0.1524)
				(type default)
			)
			(layer "F.SilkS")
		)
		(fp_line
			(start 0.7874 0.4064)
			(end -0.7874 0.4064)
			(stroke
				(width 0.1524)
				(type default)
			)
			(layer "F.SilkS")
		)
		(fp_line
			(start -0.7874 0.4064)
			(end -0.7874 -0.4064)
			(stroke
				(width 0.1524)
				(type default)
			)
			(layer "F.SilkS")
		)
		(fp_line
			(start -0.12065 -0.305054)
			(end -0.12065 -0.2794)
			(stroke
				(width 0.1)
				(type default)
			)
			(layer "F.Fab")
		)
		(fp_line
			(start -0.67945 -0.305054)
			(end -0.12065 -0.305054)
			(stroke
				(width 0.1)
				(type default)
			)
			(layer "F.Fab")
		)
		(fp_line
			(start 0.67945 -0.3048)
			(end 0.67945 0.3048)
			(stroke
				(width 0.1)
				(type default)
			)
			(layer "F.Fab")
		)
		(fp_line
			(start 0.12065 -0.3048)
			(end 0.67945 -0.3048)
			(stroke
				(width 0.1)
				(type default)
			)
			(layer "F.Fab")
		)
		(fp_line
			(start 0.12065 -0.2794)
			(end 0.12065 -0.3048)
			(stroke
				(width 0.1)
				(type default)
			)
			(layer "F.Fab")
		)
		(fp_line
			(start -0.12065 -0.2794)
			(end 0.12065 -0.2794)
			(stroke
				(width 0.1)
				(type default)
			)
			(layer "F.Fab")
		)
		(fp_line
			(start 0.120396 0.2794)
			(end -0.12065 0.2794)
			(stroke
				(width 0.1)
				(type default)
			)
			(layer "F.Fab")
		)
		(fp_line
			(start -0.12065 0.2794)
			(end -0.12065 0.3048)
			(stroke
				(width 0.1)
				(type default)
			)
			(layer "F.Fab")
		)
		(fp_line
			(start 0.67945 0.3048)
			(end 0.120396 0.3048)
			(stroke
				(width 0.1)
				(type default)
			)
			(layer "F.Fab")
		)
		(fp_line
			(start 0.120396 0.3048)
			(end 0.120396 0.2794)
			(stroke
				(width 0.1)
				(type default)
			)
			(layer "F.Fab")
		)
		(fp_line
			(start -0.12065 0.3048)
			(end -0.67945 0.3048)
			(stroke
				(width 0.1)
				(type default)
			)
			(layer "F.Fab")
		)
		(fp_line
			(start -0.67945 0.3048)
			(end -0.67945 -0.305054)
			(stroke
				(width 0.1)
				(type default)
			)
			(layer "F.Fab")
		)
		(pad "1" smd circle
			(at -0.40005 0 90)
			(size 0 0)
			(layers "F.Cu" "F.Mask" "F.Paste")
			(net "PVDD_33_S5")
		)
		(pad "2" smd circle
			(at 0.40005 0 90)
			(size 0 0)
			(layers "F.Cu" "F.Mask" "F.Paste")
			(net "GND")
		)
	)
	(footprint ""
		(layer "F.Cu")
		(at 303.023778 -46.444154)
		(property "Reference" "L16"
			(at 0 0 0)
			(layer "F.SilkS")
			(hide yes)
			(effects
				(font
					(size 1.27 1.27)
				)
			)
		)
		(property "Value" ""
			(at 0 0 0)
			(layer "F.Fab")
			(effects
				(font
					(size 1.27 1.27)
				)
			)
		)
		(duplicate_pad_numbers_are_jumpers no)
		(fp_line
			(start -1.27 -0.5842)
			(end 1.27 -0.5842)
			(stroke
				(width 0.1524)
				(type default)
			)
			(layer "F.SilkS")
		)
		(fp_line
			(start -1.27 -0.5588)
			(end -1.27 -0.5842)
			(stroke
				(width 0.1524)
				(type default)
			)
			(layer "F.SilkS")
		)
		(fp_line
			(start -1.27 0.5842)
			(end -1.27 -0.5842)
			(stroke
				(width 0.1524)
				(type default)
			)
			(layer "F.SilkS")
		)
		(fp_line
			(start 1.27 0.5842)
			(end -1.27 0.5842)
			(stroke
				(width 0.1524)
				(type default)
			)
			(layer "F.SilkS")
		)
		(fp_line
			(start 1.27 0.5842)
			(end 1.27 -0.5842)
			(stroke
				(width 0.1524)
				(type default)
			)
			(layer "F.SilkS")
		)
		(fp_line
			(start -1.194308 -0.406654)
			(end -0.9144 -0.406654)
			(stroke
				(width 0.1)
				(type default)
			)
			(layer "F.Fab")
		)
		(fp_line
			(start -1.194308 0.406654)
			(end -1.194308 -0.406654)
			(stroke
				(width 0.1)
				(type default)
			)
			(layer "F.Fab")
		)
		(fp_line
			(start -0.9144 -0.508)
			(end 0.9144 -0.508)
			(stroke
				(width 0.1)
				(type default)
			)
			(layer "F.Fab")
		)
		(fp_line
			(start -0.9144 -0.406654)
			(end -0.9144 -0.508)
			(stroke
				(width 0.1)
				(type default)
			)
			(layer "F.Fab")
		)
		(fp_line
			(start -0.9144 0.406654)
			(end -1.194308 0.406654)
			(stroke
				(width 0.1)
				(type default)
			)
			(layer "F.Fab")
		)
		(fp_line
			(start -0.9144 0.508)
			(end -0.9144 0.406654)
			(stroke
				(width 0.1)
				(type default)
			)
			(layer "F.Fab")
		)
		(fp_line
			(start 0.9144 -0.508)
			(end 0.9144 -0.406654)
			(stroke
				(width 0.1)
				(type default)
			)
			(layer "F.Fab")
		)
		(fp_line
			(start 0.9144 -0.406654)
			(end 1.1938 -0.406654)
			(stroke
				(width 0.1)
				(type default)
			)
			(layer "F.Fab")
		)
		(fp_line
			(start 0.9144 0.4064)
			(end 0.9144 0.508)
			(stroke
				(width 0.1)
				(type default)
			)
			(layer "F.Fab")
		)
		(fp_line
			(start 0.9144 0.508)
			(end -0.9144 0.508)
			(stroke
				(width 0.1)
				(type default)
			)
			(layer "F.Fab")
		)
		(fp_line
			(start 1.1938 -0.406654)
			(end 1.1938 0.4064)
			(stroke
				(width 0.1)
				(type default)
			)
			(layer "F.Fab")
		)
		(fp_line
			(start 1.1938 0.4064)
			(end 0.9144 0.4064)
			(stroke
				(width 0.1)
				(type default)
			)
			(layer "F.Fab")
		)
		(pad "1" smd rect
			(at -0.7366 0 270)
			(size 0.7112 0.8128)
			(layers "F.Cu" "F.Mask" "F.Paste")
			(net "P3V3_AUX")
		)
		(pad "2" smd rect
			(at 0.7366 0 270)
			(size 0.7112 0.8128)
			(layers "F.Cu" "F.Mask" "F.Paste")
			(net "P3V3_ADC128_VCC")
		)
	)
)
